# S9S_MB_2U (Grand Teton) — schematic netlist excerpt (pin names and nets, part order shuffled) for the footprints in the layout excerpt that follows; sources: Cadence DE-HDL packaged netlist, KiCad conversion of 03242023_DA0F0TMBIJ0_F0T_Motherboard_J_brd_V01_OCP.brd

D0  Q_LED  IC  pkg SMLF  page 218 : A = PU_PLD_HEARTBEAT_LVC3 ; C = FM_PLD_HEARTBEAT_LVC3_D
R453  Q_RES  10K 1% CHIP  pkg 0402LF  page 182 : A = P3V3_AUX ; B = PU_LAN_WAKE_N

(kicad_pcb
	(version 20260206)
	(generator "pcbnew")
	(generator_version "10.0")
	(general
		(thickness 1.6)
		(legacy_teardrops no)
	)
	(paper "A4")
	(title_block
		(title "03242023_DA0F0TMBIJ0_F0T_Motherboard_J_brd_V01_OCP.brd")
		(comment 1 "Grand Teton / footprints 1569-1570 of 6105")
	)
	(layers
		(0 "F.Cu" signal "TOP")
		(4 "In1.Cu" signal "GND")
		(6 "In2.Cu" signal "IN1")
		(8 "In3.Cu" signal "GND1")
		(10 "In4.Cu" signal "IN2")
		(12 "In5.Cu" signal "GND2")
		(14 "In6.Cu" signal "IN3")
		(16 "In7.Cu" signal "GND3")
		(18 "In8.Cu" signal "VCC")
		(20 "In9.Cu" signal "VCC1")
		(22 "In10.Cu" signal "GND4")
		(24 "In11.Cu" signal "IN4")
		(26 "In12.Cu" signal "GND5")
		(28 "In13.Cu" signal "IN5")
		(30 "In14.Cu" signal "GND6")
		(32 "In15.Cu" signal "IN6")
		(34 "In16.Cu" signal "GND7")
		(2 "B.Cu" signal "BOTTOM")
		(9 "F.Adhes" user "F.Adhesive")
		(11 "B.Adhes" user "B.Adhesive")
		(13 "F.Paste" user "Package Geometry/Pastemask Top")
		(15 "B.Paste" user "Package Geometry/Pastemask Bottom")
		(5 "F.SilkS" user "Ref Des/Silkscreen Top")
		(7 "B.SilkS" user "Ref Des/Silkscreen Bottom")
		(1 "F.Mask" user "Board Geometry/Soldermask Top")
		(3 "B.Mask" user "Board Geometry/Soldermask Bottom")
		(17 "Dwgs.User" user "User.Drawings")
		(19 "Cmts.User" user "User.Comments")
		(21 "Eco1.User" user "User.Eco1")
		(23 "Eco2.User" user "User.Eco2")
		(25 "Edge.Cuts" user "Board Geometry/Outline")
		(27 "Margin" user)
		(31 "F.CrtYd" user "Package Geometry/Place Bound Top")
		(29 "B.CrtYd" user "Package Geometry/Place Bound Bottom")
		(35 "F.Fab" user "Ref Des/Assembly Top")
		(33 "B.Fab" user "Ref Des/Assembly Bottom")
	)
	(footprint ""
		(layer "F.Cu")
		(at 219.79128 -111.115348 180)
		(property "Reference" "D0"
			(at -2.3876 -0.581152 0)
			(unlocked yes)
			(layer "F.SilkS")
			(effects
				(font
					(size 0.7874 0.5842)
					(thickness 0.1524)
				)
				(justify left)
			)
		)
		(property "Value" ""
			(at 0 0 180)
			(layer "F.Fab")
			(effects
				(font
					(size 1.27 1.27)
				)
			)
		)
		(duplicate_pad_numbers_are_jumpers no)
		(fp_line
			(start 1.16078 0.4826)
			(end -0.64008 0.4826)
			(stroke
				(width 0.1524)
				(type default)
			)
			(layer "F.SilkS")
		)
		(fp_line
			(start 1.16078 -0.4826)
			(end 1.16078 0.4826)
			(stroke
				(width 0.1524)
				(type default)
			)
			(layer "F.SilkS")
		)
		(fp_line
			(start 1.03378 0.4826)
			(end -0.79248 0.4826)
			(stroke
				(width 0.1524)
				(type default)
			)
			(layer "F.SilkS")
		)
		(fp_line
			(start 1.03378 -0.4826)
			(end 1.03378 0.4826)
			(stroke
				(width 0.1524)
				(type default)
			)
			(layer "F.SilkS")
		)
		(fp_line
			(start 0.90678 0.4826)
			(end -0.90678 0.4826)
			(stroke
				(width 0.1524)
				(type default)
			)
			(layer "F.SilkS")
		)
		(fp_line
			(start 0.90678 -0.4826)
			(end 0.90678 0.4826)
			(stroke
				(width 0.1524)
				(type default)
			)
			(layer "F.SilkS")
		)
		(fp_line
			(start -0.64008 -0.4826)
			(end 1.16078 -0.4826)
			(stroke
				(width 0.1524)
				(type default)
			)
			(layer "F.SilkS")
		)
		(fp_line
			(start -0.79248 -0.4826)
			(end 1.03378 -0.4826)
			(stroke
				(width 0.1524)
				(type default)
			)
			(layer "F.SilkS")
		)
		(fp_line
			(start -0.89408 -0.4826)
			(end 0.90678 -0.4826)
			(stroke
				(width 0.1524)
				(type default)
			)
			(layer "F.SilkS")
		)
		(fp_line
			(start -0.90678 0.4826)
			(end -0.90678 -0.4699)
			(stroke
				(width 0.1524)
				(type default)
			)
			(layer "F.SilkS")
		)
		(fp_line
			(start 0.499872 0.249936)
			(end -0.499872 0.249936)
			(stroke
				(width 0.1)
				(type default)
			)
			(layer "F.Fab")
		)
		(fp_line
			(start 0.499872 -0.249936)
			(end 0.499872 0.249936)
			(stroke
				(width 0.1)
				(type default)
			)
			(layer "F.Fab")
		)
		(fp_line
			(start -0.499872 0.249936)
			(end -0.499872 -0.249936)
			(stroke
				(width 0.1)
				(type default)
			)
			(layer "F.Fab")
		)
		(fp_line
			(start -0.499872 -0.249936)
			(end 0.499872 -0.249936)
			(stroke
				(width 0.1)
				(type default)
			)
			(layer "F.Fab")
		)
		(pad "A" smd rect
			(at -0.47498 0 180)
			(size 0.6096 0.7112)
			(layers "F.Cu" "F.Mask" "F.Paste")
			(net "PU_PLD_HEARTBEAT_LVC3")
		)
		(pad "C" smd rect
			(at 0.47498 0 180)
			(size 0.6096 0.7112)
			(layers "F.Cu" "F.Mask" "F.Paste")
			(net "FM_PLD_HEARTBEAT_LVC3_D")
		)
	)
	(footprint ""
		(layer "F.Cu")
		(at 309.522622 -39.106348 180)
		(property "Reference" "R453"
			(at 0 0 180)
			(layer "F.SilkS")
			(hide yes)
			(effects
				(font
					(size 1.27 1.27)
				)
			)
		)
		(property "Value" ""
			(at 0 0 180)
			(layer "F.Fab")
			(effects
				(font
					(size 1.27 1.27)
				)
			)
		)
		(duplicate_pad_numbers_are_jumpers no)
		(fp_line
			(start 0.7874 0.4064)
			(end -0.7874 0.4064)
			(stroke
				(width 0.1524)
				(type default)
			)
			(layer "F.SilkS")
		)
		(fp_line
			(start 0.7874 -0.4064)
			(end 0.7874 0.4064)
			(stroke
				(width 0.1524)
				(type default)
			)
			(layer "F.SilkS")
		)
		(fp_line
			(start -0.7874 0.4064)
			(end -0.7874 -0.4064)
			(stroke
				(width 0.1524)
				(type default)
			)
			(layer "F.SilkS")
		)
		(fp_line
			(start -0.7874 -0.4064)
			(end 0.7874 -0.4064)
			(stroke
				(width 0.1524)
				(type default)
			)
			(layer "F.SilkS")
		)
		(fp_line
			(start 0.67945 0.3048)
			(end 0.120396 0.3048)
			(stroke
				(width 0.1)
				(type default)
			)
			(layer "F.Fab")
		)
		(fp_line
			(start 0.67945 -0.3048)
			(end 0.67945 0.3048)
			(stroke
				(width 0.1)
				(type default)
			)
			(layer "F.Fab")
		)
		(fp_line
			(start 0.12065 -0.2794)
			(end 0.12065 -0.3048)
			(stroke
				(width 0.1)
				(type default)
			)
			(layer "F.Fab")
		)
		(fp_line
			(start 0.12065 -0.3048)
			(end 0.67945 -0.3048)
			(stroke
				(width 0.1)
				(type default)
			)
			(layer "F.Fab")
		)
		(fp_line
			(start 0.120396 0.3048)
			(end 0.120396 0.2794)
			(stroke
				(width 0.1)
				(type default)
			)
			(layer "F.Fab")
		)
		(fp_line
			(start 0.120396 0.2794)
			(end -0.12065 0.2794)
			(stroke
				(width 0.1)
				(type default)
			)
			(layer "F.Fab")
		)
		(fp_line
			(start -0.12065 0.3048)
			(end -0.67945 0.3048)
			(stroke
				(width 0.1)
				(type default)
			)
			(layer "F.Fab")
		)
		(fp_line
			(start -0.12065 0.2794)
			(end -0.12065 0.3048)
			(stroke
				(width 0.1)
				(type default)
			)
			(layer "F.Fab")
		)
		(fp_line
			(start -0.12065 -0.2794)
			(end 0.12065 -0.2794)
			(stroke
				(width 0.1)
				(type default)
			)
			(layer "F.Fab")
		)
		(fp_line
			(start -0.12065 -0.305054)
			(end -0.12065 -0.2794)
			(stroke
				(width 0.1)
				(type default)
			)
			(layer "F.Fab")
		)
		(fp_line
			(start -0.67945 0.3048)
			(end -0.67945 -0.305054)
			(stroke
				(width 0.1)
				(type default)
			)
			(layer "F.Fab")
		)
		(fp_line
			(start -0.67945 -0.305054)
			(end -0.12065 -0.305054)
			(stroke
				(width 0.1)
				(type default)
			)
			(layer "F.Fab")
		)
		(pad "1" smd circle
			(at -0.40005 0 180)
			(size 0 0)
			(layers "F.Cu" "F.Mask" "F.Paste")
			(net "P3V3_AUX")
		)
		(pad "2" smd circle
			(at 0.40005 0 180)
			(size 0 0)
			(layers "F.Cu" "F.Mask" "F.Paste")
			(net "PU_LAN_WAKE_N")
		)
	)
)
